#ISCELL
  pure_quanta quanta_title_block_c *
  *
#ISCELL
  standard offpage *
  page34_i1
#ISCELL
  standard offpage *
  page34_i104
#ISCELL
  standard offpage *
  page34_i105
#CELL
  pure_quanta q_res *
  page34_i106
#CELL
  pure_quanta q_res *
  page34_i107
#ISCELL
  pure_quanta_power universal_power *
  page34_i108
#ISCELL
  pure_quanta_power universal_gnd *
  page34_i123
#CELL
  pure_quanta q_cap *
  page34_i124
#CELL
  pure_quanta q_res *
  page34_i125
#CELL
  pure_quanta pca9617adp *
  page34_i18
#ISCELL
  standard offpage *
  page34_i2
#ISCELL
  pure_quanta_power universal_power *
  page34_i3
#CELL
  pure_quanta q_res *
  page34_i4
#ISCELL
  pure_quanta_power universal_gnd *
  page34_i40
#ISCELL
  standard offpage *
  page34_i41
#ISCELL
  standard offpage *
  page34_i42
#ISCELL
  pure_quanta_power universal_power *
  page34_i43
#CELL
  pure_quanta q_cap *
  page34_i44
#ISCELL
  pure_quanta_power universal_gnd *
  page34_i45
#ISCELL
  pure_quanta_power universal_power *
  page34_i46
#CELL
  pure_quanta q_cap *
  page34_i47
#ISCELL
  pure_quanta_power universal_gnd *
  page34_i48
#CELL
  pure_quanta q_res *
  page34_i5
#ISCELL
  standard offpage *
  page34_i50
#ISCELL
  standard offpage *
  page34_i51
#ISCELL
  standard offpage *
  page34_i52
#CELL
  pure_quanta q_res *
  page34_i53
#ISCELL
  pure_quanta_power universal_power *
  page34_i54
#CELL
  pure_quanta sn74lvc1g07dbvr *
  page34_i55
#ISCELL
  pure_quanta_power universal_gnd *
  page34_i56
#ISCELL
  pure_quanta_power universal_gnd *
  page34_i58
#CELL
  pure_quanta q_cap *
  page34_i59
#CELL
  pure_quanta q_res *
  page34_i60
#ISCELL
  standard offpage *
  page34_i61
#ISCELL
  pure_quanta_power p1v0 *
  page34_i62
